(kicad_pcb
	(version 20221018)
	(generator pcbnew)
	(general
    (thickness 1.518)
  )
	(paper "A4")
	(title_block
    (title "Kria K26 Devboard")
    (date "2024-03-26")
    (rev "1.2.5")
    (comment 1 "www.antmicro.com")
    (comment 2 "Antmicro Ltd.")
		(comment 9 "footprints 266-274 of 660")
	)
	(layers
    (0 "F.Cu" mixed)
    (1 "In1.Cu" power)
    (2 "In2.Cu" mixed)
    (3 "In3.Cu" power)
    (4 "In4.Cu" mixed)
    (5 "In5.Cu" power)
    (6 "In6.Cu" mixed)
    (31 "B.Cu" power)
    (32 "B.Adhes" user "B.Adhesive")
    (33 "F.Adhes" user "F.Adhesive")
    (34 "B.Paste" user)
    (35 "F.Paste" user)
    (36 "B.SilkS" user "B.Silkscreen")
    (37 "F.SilkS" user "F.Silkscreen")
    (38 "B.Mask" user)
    (39 "F.Mask" user)
    (40 "Dwgs.User" user "User.Drawings")
    (41 "Cmts.User" user "User.Comments")
    (42 "Eco1.User" user "User.Eco1")
    (43 "Eco2.User" user "User.Eco2")
    (44 "Edge.Cuts" user)
    (45 "Margin" user)
    (46 "B.CrtYd" user "B.Courtyard")
    (47 "F.CrtYd" user "F.Courtyard")
    (48 "B.Fab" user)
    (49 "F.Fab" user)
  )
	(footprint "kria-k26-devboard-footprints:UQFN-10_1.4x1.8x0.5mm_P0.4mm" (layer "F.Cu")
    (at 143.549916 126.012314)
    (property "Author" "Antmicro")
    (property "License" "Apache-2.0")
    (property "MPN" "SN74AVC2T245RSWR")
    (property "Manufacturer" "Texas Instruments")
    (property "Sheetfile" "debug.kicad_sch")
    (property "Sheetname" "Debug and JTAG")
    (property "ki_description" "Transceiver Non Inverting, AVC Family, 2 Input, 12 mA, 2.4 ns, 1.2 V to 3.6 V, LFCSP-10")
    (property "ki_keywords" "SMT, LOGIC, IC, LEVEL-SHIFTER, VOLTAGE")
    (attr smd)
    (fp_text reference "U45" (at -0.449916 -1.662314) (layer "F.SilkS")
        (effects (font (size 0.7 0.7) (thickness 0.15)) (justify left bottom))
    )
    (fp_text value "SN74AVC2T245_UQFN" (at 0 2.4) (layer "F.Fab") hide
        (effects (font (size 0.7 0.7) (thickness 0.15)) (justify left bottom))
    )
    (fp_text user "License: Apache-2.0" (at -0.657 6.9) (layer "F.Fab") hide
        (effects (font (size 0.7 0.7) (thickness 0.15)) (justify left bottom))
    )
    (fp_text user "Author: Antmicro" (at -0.657 5.7) (layer "F.Fab") hide
        (effects (font (size 0.7 0.7) (thickness 0.15)) (justify left bottom))
    )
    (fp_text user "${REFERENCE}" (at -0.657 4.498) (layer "F.Fab") hide
        (effects (font (size 0.7 0.7) (thickness 0.15)) (justify left bottom))
    )
    (fp_line (start -0.7305 -0.552) (end -1.2005 -0.552)
      (stroke (width 0.15) (type solid)) (layer "F.SilkS"))
    (fp_line (start -0.7305 -0.552) (end -0.7305 -0.93)
      (stroke (width 0.15) (type solid)) (layer "F.SilkS"))
    (fp_circle (center -1.0515 -1.151) (end -0.9805 -1.151)
      (stroke (width 0.15) (type solid)) (fill none) (layer "F.SilkS"))
    (fp_rect (start -1.3 -1.5) (end 1.3 1.5)
      (stroke (width 0.05) (type solid)) (fill none) (layer "F.CrtYd"))
    (fp_line (start -0.7 -0.4) (end -0.175 -0.925)
      (stroke (width 0.15) (type solid)) (layer "F.Fab"))
    (fp_line (start -0.7 0.93) (end -0.7 -0.4)
      (stroke (width 0.15) (type solid)) (layer "F.Fab"))
    (fp_line (start -0.175 -0.925) (end 0.7295 -0.925)
      (stroke (width 0.15) (type solid)) (layer "F.Fab"))
    (fp_line (start 0.725 0.93) (end -0.7 0.93)
      (stroke (width 0.15) (type solid)) (layer "F.Fab"))
    (fp_line (start 0.7295 -0.925) (end 0.725 0.93)
      (stroke (width 0.15) (type solid)) (layer "F.Fab"))
    (pad "1" smd roundrect (at -0.6445 -0.2) (size 0.81 0.22) (layers "F.Cu" "F.Paste" "F.Mask") (roundrect_rratio 0.25)
      (net 138 "/Debug and JTAG/USB_3V3") (pinfunction "DIR_{2}") (pintype "input"))
    (pad "2" smd roundrect (at -0.6445 0.2) (size 0.81 0.22) (layers "F.Cu" "F.Paste" "F.Mask") (roundrect_rratio 0.25)
      (net 1 "GND") (pinfunction "~{OE}") (pintype "input"))
    (pad "3" smd roundrect (at -0.4015 0.844 270) (size 0.81 0.22) (layers "F.Cu" "F.Paste" "F.Mask") (roundrect_rratio 0.25)
      (net 1 "GND") (pinfunction "GND") (pintype "power_in"))
    (pad "4" smd roundrect (at 0.0005 0.844 270) (size 0.81 0.22) (layers "F.Cu" "F.Paste" "F.Mask") (roundrect_rratio 0.25)
      (net 150 "/Debug and JTAG/MIO37") (pinfunction "B_{2}") (pintype "bidirectional"))
    (pad "5" smd roundrect (at 0.3995 0.844 270) (size 0.81 0.22) (layers "F.Cu" "F.Paste" "F.Mask") (roundrect_rratio 0.25)
      (net 149 "/Debug and JTAG/MIO36") (pinfunction "B_{1}") (pintype "bidirectional"))
    (pad "6" smd roundrect (at 0.6455 0.2) (size 0.81 0.22) (layers "F.Cu" "F.Paste" "F.Mask") (roundrect_rratio 0.25)
      (net 17 "PS_1V8") (pinfunction "V_{CCB}") (pintype "power_in"))
    (pad "7" smd roundrect (at 0.6455 -0.2) (size 0.81 0.22) (layers "F.Cu" "F.Paste" "F.Mask") (roundrect_rratio 0.25)
      (net 138 "/Debug and JTAG/USB_3V3") (pinfunction "V_{CCA}") (pintype "power_in"))
    (pad "8" smd roundrect (at 0.3995 -0.847 270) (size 0.81 0.22) (layers "F.Cu" "F.Paste" "F.Mask") (roundrect_rratio 0.25)
      (net 165 "/Debug and JTAG/FTDI_UARTB_RXD") (pinfunction "A_{1}") (pintype "bidirectional"))
    (pad "9" smd roundrect (at 0.0005 -0.847 270) (size 0.81 0.22) (layers "F.Cu" "F.Paste" "F.Mask") (roundrect_rratio 0.25)
      (net 166 "/Debug and JTAG/FTDI_UARTB_TXD") (pinfunction "A_{2}") (pintype "bidirectional"))
    (pad "10" smd roundrect (at -0.4015 -0.847 270) (size 0.81 0.22) (layers "F.Cu" "F.Paste" "F.Mask") (roundrect_rratio 0.25)
      (net 1 "GND") (pinfunction "DIR_{1}") (pintype "input"))
  )
	(footprint "kria-k26-devboard-footprints:FB_0402_1005Metric" (layer "F.Cu")
    (at 149.45 112.7 -90)
    (descr "Ferrite Bead SMD 0402")
    (tags "ferrite bead SMD 0402")
    (property "Author" "Antmicro")
    (property "License" "Apache-2.0")
    (property "MPN" "BLM15PD121SN1D")
    (property "Manufacturer" "Murata")
    (property "Sheetfile" "debug.kicad_sch")
    (property "Sheetname" "Debug and JTAG")
    (attr smd)
    (fp_text reference "FB5" (at 1.29 0.53 -90) (layer "F.SilkS")
        (effects (font (size 0.7 0.7) (thickness 0.15)) (justify left bottom))
    )
    (fp_text value "FB_120Z_1.3A_0402" (at 0 1.4 -90) (layer "F.Fab") hide
        (effects (font (size 0.7 0.7) (thickness 0.15)) (justify left bottom))
    )
    (fp_text user "Author: Antmicro" (at -0.95 4.169 -90) (layer "F.Fab") hide
        (effects (font (size 0.7 0.7) (thickness 0.15)) (justify left bottom))
    )
    (fp_text user "License: Apache-2.0" (at -0.95 5.169 -90) (layer "F.Fab") hide
        (effects (font (size 0.7 0.7) (thickness 0.15)) (justify left bottom))
    )
    (fp_text user "${REFERENCE}" (at -0.95 3.168 -90) (layer "F.Fab") hide
        (effects (font (size 0.7 0.7) (thickness 0.15)) (justify left bottom))
    )
    (fp_rect (start -0.95 -0.48) (end 0.95 0.48)
      (stroke (width 0.05) (type solid)) (fill none) (layer "F.CrtYd"))
    (fp_rect (start -0.5 -0.25) (end 0.5 0.25)
      (stroke (width 0.15) (type solid)) (fill none) (layer "F.Fab"))
    (pad "1" smd roundrect (at -0.485 0 270) (size 0.59 0.64) (layers "F.Cu" "F.Paste" "F.Mask") (roundrect_rratio 0.25)
      (net 138 "/Debug and JTAG/USB_3V3") (pintype "passive"))
    (pad "2" smd roundrect (at 0.485 0 270) (size 0.59 0.64) (layers "F.Cu" "F.Paste" "F.Mask") (roundrect_rratio 0.25)
      (net 135 "/Debug and JTAG/VCC_USB") (pintype "passive"))
  )
	(footprint "kria-k26-devboard-footprints:TP_SMD_0.75mm" (layer "F.Cu")
    (at 149.45 110.7)
    (property "Author" "Antmicro")
    (property "License" "Apache-2.0")
    (property "MPN" "")
    (property "Manufacturer" "")
    (property "Sheetfile" "debug.kicad_sch")
    (property "Sheetname" "Debug and JTAG")
    (property "ki_description" "Test Point 0.75mm")
    (attr exclude_from_pos_files)
    (fp_text reference "TP27" (at 0.37 -0.36 90) (layer "F.SilkS")
        (effects (font (size 0.7 0.7) (thickness 0.15)) (justify left bottom))
    )
    (fp_text value "TP_0.75mm_SMD" (at 0 1.2) (layer "F.Fab") hide
        (effects (font (size 0.7 0.7) (thickness 0.15)) (justify left bottom))
    )
    (fp_text user "${REFERENCE}" (at -0.4 2.7) (layer "F.Fab") hide
        (effects (font (size 0.7 0.7) (thickness 0.15)) (justify left bottom))
    )
    (fp_text user "License: Apache-2.0" (at -0.4 5.101) (layer "F.Fab") hide
        (effects (font (size 0.7 0.7) (thickness 0.15)) (justify left bottom))
    )
    (fp_text user "Author: Antmicro" (at -0.4 3.901) (layer "F.Fab") hide
        (effects (font (size 0.7 0.7) (thickness 0.15)) (justify left bottom))
    )
    (pad "1" smd circle (at 0 0) (size 0.75 0.75) (layers "F.Cu" "F.Mask")
      (net 138 "/Debug and JTAG/USB_3V3") (pinfunction "1") (pintype "passive"))
  )
	(footprint "kria-k26-devboard-footprints:SOT-416" (layer "F.Cu")
    (at 136.395 128.18 180)
    (descr "SOT-416")
    (tags "SOT-416")
    (property "Author" "Antmicro")
    (property "License" "Apache-2.0")
    (property "MPN" "DTC014TEBTL")
    (property "Manufacturer" "ROHM Semiconductor")
    (property "Sheetfile" "debug.kicad_sch")
    (property "Sheetname" "Debug and JTAG")
    (property "ki_description" "Digital NPN Transistor, 10k/NONE, EMT-3")
    (attr smd)
    (fp_text reference "Q10" (at 3.175 -0.01 180) (layer "F.SilkS")
        (effects (font (size 0.7 0.7) (thickness 0.15)) (justify left bottom))
    )
    (fp_text value "DTC014T_SOT-416" (at 0 2 180) (layer "F.Fab") hide
        (effects (font (size 0.7 0.7) (thickness 0.15)) (justify left bottom))
    )
    (fp_text user "License: Apache-2.0" (at -1 5.802 180) (layer "F.Fab") hide
        (effects (font (size 0.7 0.7) (thickness 0.15)) (justify left bottom))
    )
    (fp_text user "${REFERENCE}" (at -1 3.4 180) (layer "F.Fab") hide
        (effects (font (size 0.7 0.7) (thickness 0.15)) (justify left bottom))
    )
    (fp_text user "Author: Antmicro" (at -1 4.602 180) (layer "F.Fab") hide
        (effects (font (size 0.7 0.7) (thickness 0.15)) (justify left bottom))
    )
    (fp_line (start -0.5 -0.15) (end -0.5 0.15)
      (stroke (width 0.15) (type solid)) (layer "F.SilkS"))
    (fp_line (start 0.5 0.9) (end -0.5 0.9)
      (stroke (width 0.15) (type solid)) (layer "F.SilkS"))
    (fp_line (start 0.5 0.9) (end 0.5 0.7)
      (stroke (width 0.15) (type solid)) (layer "F.SilkS"))
    (fp_line (start 0.508 -0.9) (end -0.5 -0.9)
      (stroke (width 0.15) (type solid)) (layer "F.SilkS"))
    (fp_line (start 0.508 -0.9) (end 0.508 -0.592)
      (stroke (width 0.15) (type solid)) (layer "F.SilkS"))
    (fp_rect (start -1 -1.05) (end 1 1.05)
      (stroke (width 0.05) (type solid)) (fill none) (layer "F.CrtYd"))
    (fp_line (start -0.05 -0.9) (end -0.45 -0.5)
      (stroke (width 0.15) (type solid)) (layer "F.Fab"))
    (fp_rect (start 0.45 0.9) (end -0.45 -0.9)
      (stroke (width 0.15) (type solid)) (fill none) (layer "F.Fab"))
    (pad "1" smd rect (at -0.652 -0.5 180) (size 0.6 0.5) (layers "F.Cu" "F.Paste" "F.Mask")
      (net 159 "/Debug and JTAG/~{FTDI_LS_OE}") (pinfunction "B") (pintype "input"))
    (pad "2" smd rect (at -0.652 0.498 180) (size 0.6 0.5) (layers "F.Cu" "F.Paste" "F.Mask")
      (net 1 "GND") (pinfunction "E") (pintype "passive"))
    (pad "3" smd rect (at 0.65 0 180) (size 0.6 0.5) (layers "F.Cu" "F.Paste" "F.Mask")
      (net 220 "/Debug and JTAG/CONN_GND") (pinfunction "C") (pintype "passive"))
  )
	(footprint "kria-k26-devboard-footprints:R_0402_1005Metric" (layer "F.Cu")
    (at 91.28 71.4 180)
    (descr "Resistor SMD 0402")
    (tags "resistor SMD 0402")
    (property "Author" "Antmicro")
    (property "License" "Apache-2.0")
    (property "MPN" "CR0402-FX-1003GLF")
    (property "Manufacturer" "Bourns")
    (property "Sheetfile" "dp.kicad_sch")
    (property "Sheetname" "Display Port")
    (property "Tolerance" "1%")
    (property "Val" "100k")
    (property "ki_description" "100k resistor in 0402 package with 1% tolerance")
    (attr smd)
    (fp_text reference "R8" (at -6.255 -0.353 180) (layer "F.SilkS")
        (effects (font (size 0.7 0.7) (thickness 0.15)) (justify left bottom))
    )
    (fp_text value "R_100k_0402" (at 0 1.4 180) (layer "F.Fab") hide
        (effects (font (size 0.7 0.7) (thickness 0.15)) (justify left bottom))
    )
    (fp_text user "License: Apache-2.0" (at -0.95 5.169 180) (layer "F.Fab") hide
        (effects (font (size 0.7 0.7) (thickness 0.15)) (justify left bottom))
    )
    (fp_text user "${REFERENCE}" (at -0.95 3.168 180) (layer "F.Fab") hide
        (effects (font (size 0.7 0.7) (thickness 0.15)) (justify left bottom))
    )
    (fp_text user "Author: Antmicro" (at -0.95 4.169 180) (layer "F.Fab") hide
        (effects (font (size 0.7 0.7) (thickness 0.15)) (justify left bottom))
    )
    (fp_rect (start -0.93 -0.47) (end 0.93 0.47)
      (stroke (width 0.05) (type solid)) (fill none) (layer "F.CrtYd"))
    (fp_rect (start -0.5 -0.25) (end 0.5 0.25)
      (stroke (width 0.15) (type solid)) (fill none) (layer "F.Fab"))
    (pad "1" smd roundrect (at -0.485 0 180) (size 0.59 0.64) (layers "F.Cu" "F.Paste" "F.Mask") (roundrect_rratio 0.25)
      (net 97 "/Display Port/DP_AUX_C_P") (pintype "passive"))
    (pad "2" smd roundrect (at 0.485 0 180) (size 0.59 0.64) (layers "F.Cu" "F.Paste" "F.Mask") (roundrect_rratio 0.25)
      (net 1 "GND") (pintype "passive"))
  )
	(footprint "kria-k26-devboard-footprints:R_0402_1005Metric" (layer "F.Cu")
    (at 93.23 71.4 180)
    (descr "Resistor SMD 0402")
    (tags "resistor SMD 0402")
    (property "Author" "Antmicro")
    (property "License" "Apache-2.0")
    (property "MPN" "CR0402-FX-1003GLF")
    (property "Manufacturer" "Bourns")
    (property "Sheetfile" "dp.kicad_sch")
    (property "Sheetname" "Display Port")
    (property "Tolerance" "1%")
    (property "Val" "100k")
    (property "ki_description" "100k resistor in 0402 package with 1% tolerance")
    (attr smd)
    (fp_text reference "R7" (at -6.145 -0.353 180) (layer "F.SilkS")
        (effects (font (size 0.7 0.7) (thickness 0.15)) (justify left bottom))
    )
    (fp_text value "R_100k_0402" (at 0 1.4 180) (layer "F.Fab") hide
        (effects (font (size 0.7 0.7) (thickness 0.15)) (justify left bottom))
    )
    (fp_text user "Author: Antmicro" (at -0.95 4.169 180) (layer "F.Fab") hide
        (effects (font (size 0.7 0.7) (thickness 0.15)) (justify left bottom))
    )
    (fp_text user "${REFERENCE}" (at -0.95 3.168 180) (layer "F.Fab") hide
        (effects (font (size 0.7 0.7) (thickness 0.15)) (justify left bottom))
    )
    (fp_text user "License: Apache-2.0" (at -0.95 5.169 180) (layer "F.Fab") hide
        (effects (font (size 0.7 0.7) (thickness 0.15)) (justify left bottom))
    )
    (fp_rect (start -0.93 -0.47) (end 0.93 0.47)
      (stroke (width 0.05) (type solid)) (fill none) (layer "F.CrtYd"))
    (fp_rect (start -0.5 -0.25) (end 0.5 0.25)
      (stroke (width 0.15) (type solid)) (fill none) (layer "F.Fab"))
    (pad "1" smd roundrect (at -0.485 0 180) (size 0.59 0.64) (layers "F.Cu" "F.Paste" "F.Mask") (roundrect_rratio 0.25)
      (net 15 "PS_3V3") (pintype "passive"))
    (pad "2" smd roundrect (at 0.485 0 180) (size 0.59 0.64) (layers "F.Cu" "F.Paste" "F.Mask") (roundrect_rratio 0.25)
      (net 99 "/Display Port/DP_AUX_C_N") (pintype "passive"))
  )
	(footprint "kria-k26-devboard-footprints:R_0402_1005Metric" (layer "F.Cu")
    (at 89.88 73.73 90)
    (descr "Resistor SMD 0402")
    (tags "resistor SMD 0402")
    (property "Author" "Antmicro")
    (property "License" "Apache-2.0")
    (property "MPN" "CR0402-FX-1501GLF")
    (property "Manufacturer" "Bourns")
    (property "Sheetfile" "dp.kicad_sch")
    (property "Sheetname" "Display Port")
    (property "Tolerance" "1%")
    (property "Val" "1k5")
    (property "ki_description" "1k5 resistor in 0402 package with 1% tolerance")
    (attr smd)
    (fp_text reference "R6" (at -0.803 7.475 90) (layer "F.SilkS")
        (effects (font (size 0.7 0.7) (thickness 0.15)) (justify left bottom))
    )
    (fp_text value "R_1k5_0402" (at 0 1.4 90) (layer "F.Fab") hide
        (effects (font (size 0.7 0.7) (thickness 0.15)) (justify left bottom))
    )
    (fp_text user "License: Apache-2.0" (at -0.95 5.169 90) (layer "F.Fab") hide
        (effects (font (size 0.7 0.7) (thickness 0.15)) (justify left bottom))
    )
    (fp_text user "Author: Antmicro" (at -0.95 4.169 90) (layer "F.Fab") hide
        (effects (font (size 0.7 0.7) (thickness 0.15)) (justify left bottom))
    )
    (fp_text user "${REFERENCE}" (at -0.95 3.168 90) (layer "F.Fab") hide
        (effects (font (size 0.7 0.7) (thickness 0.15)) (justify left bottom))
    )
    (fp_rect (start -0.93 -0.47) (end 0.93 0.47)
      (stroke (width 0.05) (type solid)) (fill none) (layer "F.CrtYd"))
    (fp_rect (start -0.5 -0.25) (end 0.5 0.25)
      (stroke (width 0.15) (type solid)) (fill none) (layer "F.Fab"))
    (pad "1" smd roundrect (at -0.485 0 90) (size 0.59 0.64) (layers "F.Cu" "F.Paste" "F.Mask") (roundrect_rratio 0.25)
      (net 380 "Net-(R3-Pad2)") (pintype "passive"))
    (pad "2" smd roundrect (at 0.485 0 90) (size 0.59 0.64) (layers "F.Cu" "F.Paste" "F.Mask") (roundrect_rratio 0.25)
      (net 1 "GND") (pintype "passive"))
  )
	(footprint "kria-k26-devboard-footprints:R_0402_1005Metric" (layer "F.Cu")
    (at 94.605 73.717 -90)
    (descr "Resistor SMD 0402")
    (tags "resistor SMD 0402")
    (property "Author" "Antmicro")
    (property "License" "Apache-2.0")
    (property "MPN" "CR0402-FX-2491GLF")
    (property "Manufacturer" "Bourns")
    (property "Sheetfile" "dp.kicad_sch")
    (property "Sheetname" "Display Port")
    (property "Tolerance" "1%")
    (property "Val" "2k49")
    (property "ki_description" "2k49 resistor in 0402 package with 1% tolerance")
    (attr smd)
    (fp_text reference "R5" (at 0.903 -7.325 -90) (layer "F.SilkS")
        (effects (font (size 0.7 0.7) (thickness 0.15)) (justify left bottom))
    )
    (fp_text value "R_2k49_0402" (at 0 1.4 -90) (layer "F.Fab") hide
        (effects (font (size 0.7 0.7) (thickness 0.15)) (justify left bottom))
    )
    (fp_text user "License: Apache-2.0" (at -0.95 5.169 -90) (layer "F.Fab") hide
        (effects (font (size 0.7 0.7) (thickness 0.15)) (justify left bottom))
    )
    (fp_text user "Author: Antmicro" (at -0.95 4.169 -90) (layer "F.Fab") hide
        (effects (font (size 0.7 0.7) (thickness 0.15)) (justify left bottom))
    )
    (fp_text user "${REFERENCE}" (at -0.95 3.168 -90) (layer "F.Fab") hide
        (effects (font (size 0.7 0.7) (thickness 0.15)) (justify left bottom))
    )
    (fp_rect (start -0.93 -0.47) (end 0.93 0.47)
      (stroke (width 0.05) (type solid)) (fill none) (layer "F.CrtYd"))
    (fp_rect (start -0.5 -0.25) (end 0.5 0.25)
      (stroke (width 0.15) (type solid)) (fill none) (layer "F.Fab"))
    (pad "1" smd roundrect (at -0.485 0 270) (size 0.59 0.64) (layers "F.Cu" "F.Paste" "F.Mask") (roundrect_rratio 0.25)
      (net 15 "PS_3V3") (pintype "passive"))
    (pad "2" smd roundrect (at 0.485 0 270) (size 0.59 0.64) (layers "F.Cu" "F.Paste" "F.Mask") (roundrect_rratio 0.25)
      (net 380 "Net-(R3-Pad2)") (pintype "passive"))
  )
	(footprint "kria-k26-devboard-footprints:R_0402_1005Metric" (layer "F.Cu")
    (at 93.2 74.23)
    (descr "Resistor SMD 0402")
    (tags "resistor SMD 0402")
    (property "Author" "Antmicro")
    (property "License" "Apache-2.0")
    (property "MPN" "CR0402-FX-49R9GLF")
    (property "Manufacturer" "Bourns")
    (property "Sheetfile" "dp.kicad_sch")
    (property "Sheetname" "Display Port")
    (property "Tolerance" "1%")
    (property "Val" "49R9")
    (property "ki_description" "49R9 resistor in 0402 package with 1% tolerance")
    (attr smd)
    (fp_text reference "R4" (at 6.145 0.523) (layer "F.SilkS")
        (effects (font (size 0.7 0.7) (thickness 0.15)) (justify left bottom))
    )
    (fp_text value "R_49R9_0402" (at 0 1.4) (layer "F.Fab") hide
        (effects (font (size 0.7 0.7) (thickness 0.15)) (justify left bottom))
    )
    (fp_text user "License: Apache-2.0" (at -0.95 5.169) (layer "F.Fab") hide
        (effects (font (size 0.7 0.7) (thickness 0.15)) (justify left bottom))
    )
    (fp_text user "Author: Antmicro" (at -0.95 4.169) (layer "F.Fab") hide
        (effects (font (size 0.7 0.7) (thickness 0.15)) (justify left bottom))
    )
    (fp_text user "${REFERENCE}" (at -0.95 3.168) (layer "F.Fab") hide
        (effects (font (size 0.7 0.7) (thickness 0.15)) (justify left bottom))
    )
    (fp_rect (start -0.93 -0.47) (end 0.93 0.47)
      (stroke (width 0.05) (type solid)) (fill none) (layer "F.CrtYd"))
    (fp_rect (start -0.5 -0.25) (end 0.5 0.25)
      (stroke (width 0.15) (type solid)) (fill none) (layer "F.Fab"))
    (pad "1" smd roundrect (at -0.485 0) (size 0.59 0.64) (layers "F.Cu" "F.Paste" "F.Mask") (roundrect_rratio 0.25)
      (net 98 "/Display Port/DP_AUX_N") (pintype "passive"))
    (pad "2" smd roundrect (at 0.485 0) (size 0.59 0.64) (layers "F.Cu" "F.Paste" "F.Mask") (roundrect_rratio 0.25)
      (net 380 "Net-(R3-Pad2)") (pintype "passive"))
  )
)
